(kicad_pcb
	(version 20260206)
	(generator "pcbnew")
	(generator_version "10.0")
	(general
		(thickness 1.6)
		(legacy_teardrops no)
	)
	(paper "A4")
	(title_block
		(title "04192023_DAF0TMB3IC0_F0TG_MB_C_brd_V02_OCP.brd")
		(comment 1 "Grand Teton / footprints 8015-8021 of 8354")
	)
	(layers
		(0 "F.Cu" signal "TOP")
		(4 "In1.Cu" signal "GND")
		(6 "In2.Cu" signal "IN1")
		(8 "In3.Cu" signal "GND1")
		(10 "In4.Cu" signal "IN2")
		(12 "In5.Cu" signal "GND2")
		(14 "In6.Cu" signal "IN3")
		(16 "In7.Cu" signal "GND3")
		(18 "In8.Cu" signal "VCC")
		(20 "In9.Cu" signal "VCC1")
		(22 "In10.Cu" signal "GND4")
		(24 "In11.Cu" signal "IN4")
		(26 "In12.Cu" signal "GND5")
		(28 "In13.Cu" signal "IN5")
		(30 "In14.Cu" signal "GND6")
		(32 "In15.Cu" signal "IN6")
		(34 "In16.Cu" signal "GND7")
		(2 "B.Cu" signal "BOTTOM")
		(9 "F.Adhes" user "F.Adhesive")
		(11 "B.Adhes" user "B.Adhesive")
		(13 "F.Paste" user "Package Geometry/Pastemask Top")
		(15 "B.Paste" user "Package Geometry/Pastemask Bottom")
		(5 "F.SilkS" user "Ref Des/Silkscreen Top")
		(7 "B.SilkS" user "Ref Des/Silkscreen Bottom")
		(1 "F.Mask" user "Board Geometry/Soldermask Top")
		(3 "B.Mask" user "Board Geometry/Soldermask Bottom")
		(17 "Dwgs.User" user "User.Drawings")
		(19 "Cmts.User" user "User.Comments")
		(21 "Eco1.User" user "User.Eco1")
		(23 "Eco2.User" user "User.Eco2")
		(25 "Edge.Cuts" user "Board Geometry/Outline")
		(27 "Margin" user)
		(31 "F.CrtYd" user "Package Geometry/Place Bound Top")
		(29 "B.CrtYd" user "Package Geometry/Place Bound Bottom")
		(35 "F.Fab" user "Ref Des/Assembly Top")
		(33 "B.Fab" user "Ref Des/Assembly Bottom")
	)
	(footprint ""
		(layer "B.Cu")
		(at 229.997 -218.059 90)
		(property "Reference" "R206"
			(at 0 0 90)
			(layer "B.SilkS")
			(hide yes)
			(effects
				(font
					(size 1.27 1.27)
				)
				(justify mirror)
			)
		)
		(property "Value" ""
			(at 0 0 90)
			(layer "B.Fab")
			(effects
				(font
					(size 1.27 1.27)
				)
				(justify mirror)
			)
		)
		(duplicate_pad_numbers_are_jumpers no)
		(fp_line
			(start 0.7874 -0.4064)
			(end -0.7874 -0.4064)
			(stroke
				(width 0.1524)
				(type default)
			)
			(layer "B.SilkS")
		)
		(fp_line
			(start -0.7874 -0.4064)
			(end -0.7874 0.4064)
			(stroke
				(width 0.1524)
				(type default)
			)
			(layer "B.SilkS")
		)
		(fp_line
			(start 0.7874 0.4064)
			(end 0.7874 -0.4064)
			(stroke
				(width 0.1524)
				(type default)
			)
			(layer "B.SilkS")
		)
		(fp_line
			(start -0.7874 0.4064)
			(end 0.7874 0.4064)
			(stroke
				(width 0.1524)
				(type default)
			)
			(layer "B.SilkS")
		)
		(fp_line
			(start 0.67945 -0.305054)
			(end 0.12065 -0.305054)
			(stroke
				(width 0.1)
				(type default)
			)
			(layer "B.Fab")
		)
		(fp_line
			(start 0.12065 -0.305054)
			(end 0.12065 -0.2794)
			(stroke
				(width 0.1)
				(type default)
			)
			(layer "B.Fab")
		)
		(fp_line
			(start -0.12065 -0.3048)
			(end -0.67945 -0.3048)
			(stroke
				(width 0.1)
				(type default)
			)
			(layer "B.Fab")
		)
		(fp_line
			(start -0.67945 -0.3048)
			(end -0.67945 0.3048)
			(stroke
				(width 0.1)
				(type default)
			)
			(layer "B.Fab")
		)
		(fp_line
			(start 0.12065 -0.2794)
			(end -0.12065 -0.2794)
			(stroke
				(width 0.1)
				(type default)
			)
			(layer "B.Fab")
		)
		(fp_line
			(start -0.12065 -0.2794)
			(end -0.12065 -0.3048)
			(stroke
				(width 0.1)
				(type default)
			)
			(layer "B.Fab")
		)
		(fp_line
			(start 0.12065 0.2794)
			(end 0.12065 0.3048)
			(stroke
				(width 0.1)
				(type default)
			)
			(layer "B.Fab")
		)
		(fp_line
			(start -0.120396 0.2794)
			(end 0.12065 0.2794)
			(stroke
				(width 0.1)
				(type default)
			)
			(layer "B.Fab")
		)
		(fp_line
			(start 0.67945 0.3048)
			(end 0.67945 -0.305054)
			(stroke
				(width 0.1)
				(type default)
			)
			(layer "B.Fab")
		)
		(fp_line
			(start 0.12065 0.3048)
			(end 0.67945 0.3048)
			(stroke
				(width 0.1)
				(type default)
			)
			(layer "B.Fab")
		)
		(fp_line
			(start -0.120396 0.3048)
			(end -0.120396 0.2794)
			(stroke
				(width 0.1)
				(type default)
			)
			(layer "B.Fab")
		)
		(fp_line
			(start -0.67945 0.3048)
			(end -0.120396 0.3048)
			(stroke
				(width 0.1)
				(type default)
			)
			(layer "B.Fab")
		)
		(pad "1" smd circle
			(at 0.40005 0 270)
			(size 0 0)
			(layers "B.Cu" "B.Mask" "B.Paste")
			(net "SMB_CPU0_CPU1_APML_BUF2_SDA_R1")
		)
		(pad "2" smd circle
			(at -0.40005 0 270)
			(size 0 0)
			(layers "B.Cu" "B.Mask" "B.Paste")
			(net "SMB_CPU0_CPU1_APML_BUF2_SDA_R2")
		)
	)
	(footprint ""
		(layer "B.Cu")
		(at 188.101224 -145.585434 180)
		(property "Reference" "R1197"
			(at 0 0 0)
			(layer "B.SilkS")
			(hide yes)
			(effects
				(font
					(size 1.27 1.27)
				)
				(justify mirror)
			)
		)
		(property "Value" ""
			(at 0 0 0)
			(layer "B.Fab")
			(effects
				(font
					(size 1.27 1.27)
				)
				(justify mirror)
			)
		)
		(duplicate_pad_numbers_are_jumpers no)
		(fp_line
			(start 0.7874 0.4064)
			(end 0.7874 -0.4064)
			(stroke
				(width 0.1524)
				(type default)
			)
			(layer "B.SilkS")
		)
		(fp_line
			(start 0.7874 -0.4064)
			(end -0.7874 -0.4064)
			(stroke
				(width 0.1524)
				(type default)
			)
			(layer "B.SilkS")
		)
		(fp_line
			(start -0.7874 0.4064)
			(end 0.7874 0.4064)
			(stroke
				(width 0.1524)
				(type default)
			)
			(layer "B.SilkS")
		)
		(fp_line
			(start -0.7874 -0.4064)
			(end -0.7874 0.4064)
			(stroke
				(width 0.1524)
				(type default)
			)
			(layer "B.SilkS")
		)
		(fp_line
			(start 0.67945 0.3048)
			(end 0.67945 -0.305054)
			(stroke
				(width 0.1)
				(type default)
			)
			(layer "B.Fab")
		)
		(fp_line
			(start 0.67945 -0.305054)
			(end 0.12065 -0.305054)
			(stroke
				(width 0.1)
				(type default)
			)
			(layer "B.Fab")
		)
		(fp_line
			(start 0.12065 0.3048)
			(end 0.67945 0.3048)
			(stroke
				(width 0.1)
				(type default)
			)
			(layer "B.Fab")
		)
		(fp_line
			(start 0.12065 0.2794)
			(end 0.12065 0.3048)
			(stroke
				(width 0.1)
				(type default)
			)
			(layer "B.Fab")
		)
		(fp_line
			(start 0.12065 -0.2794)
			(end -0.12065 -0.2794)
			(stroke
				(width 0.1)
				(type default)
			)
			(layer "B.Fab")
		)
		(fp_line
			(start 0.12065 -0.305054)
			(end 0.12065 -0.2794)
			(stroke
				(width 0.1)
				(type default)
			)
			(layer "B.Fab")
		)
		(fp_line
			(start -0.120396 0.3048)
			(end -0.120396 0.2794)
			(stroke
				(width 0.1)
				(type default)
			)
			(layer "B.Fab")
		)
		(fp_line
			(start -0.120396 0.2794)
			(end 0.12065 0.2794)
			(stroke
				(width 0.1)
				(type default)
			)
			(layer "B.Fab")
		)
		(fp_line
			(start -0.12065 -0.2794)
			(end -0.12065 -0.3048)
			(stroke
				(width 0.1)
				(type default)
			)
			(layer "B.Fab")
		)
		(fp_line
			(start -0.12065 -0.3048)
			(end -0.67945 -0.3048)
			(stroke
				(width 0.1)
				(type default)
			)
			(layer "B.Fab")
		)
		(fp_line
			(start -0.67945 0.3048)
			(end -0.120396 0.3048)
			(stroke
				(width 0.1)
				(type default)
			)
			(layer "B.Fab")
		)
		(fp_line
			(start -0.67945 -0.3048)
			(end -0.67945 0.3048)
			(stroke
				(width 0.1)
				(type default)
			)
			(layer "B.Fab")
		)
		(pad "1" smd circle
			(at 0.40005 0)
			(size 0 0)
			(layers "B.Cu" "B.Mask" "B.Paste")
			(net "ESPI_CPU0_ALERT_P0_N")
		)
		(pad "2" smd circle
			(at -0.40005 0)
			(size 0 0)
			(layers "B.Cu" "B.Mask" "B.Paste")
			(net "ESPI_CPU0_ALERT_N")
		)
	)
	(footprint ""
		(layer "B.Cu")
		(at 124.97689 -248.479564)
		(property "Reference" "C2333"
			(at 0 0 0)
			(layer "B.SilkS")
			(hide yes)
			(effects
				(font
					(size 1.27 1.27)
				)
				(justify mirror)
			)
		)
		(property "Value" ""
			(at 0 0 0)
			(layer "B.Fab")
			(effects
				(font
					(size 1.27 1.27)
				)
				(justify mirror)
			)
		)
		(duplicate_pad_numbers_are_jumpers no)
		(fp_line
			(start -0.7874 -0.4064)
			(end -0.7874 0.4064)
			(stroke
				(width 0.1524)
				(type default)
			)
			(layer "B.SilkS")
		)
		(fp_line
			(start -0.7874 0.4064)
			(end 0.7874 0.4064)
			(stroke
				(width 0.1524)
				(type default)
			)
			(layer "B.SilkS")
		)
		(fp_line
			(start 0.7874 -0.4064)
			(end -0.7874 -0.4064)
			(stroke
				(width 0.1524)
				(type default)
			)
			(layer "B.SilkS")
		)
		(fp_line
			(start 0.7874 0.4064)
			(end 0.7874 -0.4064)
			(stroke
				(width 0.1524)
				(type default)
			)
			(layer "B.SilkS")
		)
		(fp_line
			(start -0.67945 -0.3048)
			(end -0.67945 0.3048)
			(stroke
				(width 0.1)
				(type default)
			)
			(layer "B.Fab")
		)
		(fp_line
			(start -0.67945 0.3048)
			(end -0.120396 0.3048)
			(stroke
				(width 0.1)
				(type default)
			)
			(layer "B.Fab")
		)
		(fp_line
			(start -0.12065 -0.3048)
			(end -0.67945 -0.3048)
			(stroke
				(width 0.1)
				(type default)
			)
			(layer "B.Fab")
		)
		(fp_line
			(start -0.12065 -0.2794)
			(end -0.12065 -0.3048)
			(stroke
				(width 0.1)
				(type default)
			)
			(layer "B.Fab")
		)
		(fp_line
			(start -0.120396 0.2794)
			(end 0.12065 0.2794)
			(stroke
				(width 0.1)
				(type default)
			)
			(layer "B.Fab")
		)
		(fp_line
			(start -0.120396 0.3048)
			(end -0.120396 0.2794)
			(stroke
				(width 0.1)
				(type default)
			)
			(layer "B.Fab")
		)
		(fp_line
			(start 0.12065 -0.305054)
			(end 0.12065 -0.2794)
			(stroke
				(width 0.1)
				(type default)
			)
			(layer "B.Fab")
		)
		(fp_line
			(start 0.12065 -0.2794)
			(end -0.12065 -0.2794)
			(stroke
				(width 0.1)
				(type default)
			)
			(layer "B.Fab")
		)
		(fp_line
			(start 0.12065 0.2794)
			(end 0.12065 0.3048)
			(stroke
				(width 0.1)
				(type default)
			)
			(layer "B.Fab")
		)
		(fp_line
			(start 0.12065 0.3048)
			(end 0.67945 0.3048)
			(stroke
				(width 0.1)
				(type default)
			)
			(layer "B.Fab")
		)
		(fp_line
			(start 0.67945 -0.305054)
			(end 0.12065 -0.305054)
			(stroke
				(width 0.1)
				(type default)
			)
			(layer "B.Fab")
		)
		(fp_line
			(start 0.67945 0.3048)
			(end 0.67945 -0.305054)
			(stroke
				(width 0.1)
				(type default)
			)
			(layer "B.Fab")
		)
		(pad "1" smd circle
			(at 0.40005 0 180)
			(size 0 0)
			(layers "B.Cu" "B.Mask" "B.Paste")
			(net "PVDDCR_CPU0_P1")
		)
		(pad "2" smd circle
			(at -0.40005 0 180)
			(size 0 0)
			(layers "B.Cu" "B.Mask" "B.Paste")
			(net "GND")
		)
	)
	(footprint ""
		(layer "B.Cu")
		(at 352.718878 -398.942052 90)
		(property "Reference" "C652"
			(at 0 0 90)
			(layer "B.SilkS")
			(hide yes)
			(effects
				(font
					(size 1.27 1.27)
				)
				(justify mirror)
			)
		)
		(property "Value" ""
			(at 0 0 90)
			(layer "B.Fab")
			(effects
				(font
					(size 1.27 1.27)
				)
				(justify mirror)
			)
		)
		(duplicate_pad_numbers_are_jumpers no)
		(fp_line
			(start 0.7874 -0.4064)
			(end -0.7874 -0.4064)
			(stroke
				(width 0.1524)
				(type default)
			)
			(layer "B.SilkS")
		)
		(fp_line
			(start -0.7874 -0.4064)
			(end -0.7874 0.4064)
			(stroke
				(width 0.1524)
				(type default)
			)
			(layer "B.SilkS")
		)
		(fp_line
			(start 0.7874 0.4064)
			(end 0.7874 -0.4064)
			(stroke
				(width 0.1524)
				(type default)
			)
			(layer "B.SilkS")
		)
		(fp_line
			(start -0.7874 0.4064)
			(end 0.7874 0.4064)
			(stroke
				(width 0.1524)
				(type default)
			)
			(layer "B.SilkS")
		)
		(fp_line
			(start 0.67945 -0.305054)
			(end 0.12065 -0.305054)
			(stroke
				(width 0.1)
				(type default)
			)
			(layer "B.Fab")
		)
		(fp_line
			(start 0.12065 -0.305054)
			(end 0.12065 -0.2794)
			(stroke
				(width 0.1)
				(type default)
			)
			(layer "B.Fab")
		)
		(fp_line
			(start -0.12065 -0.3048)
			(end -0.67945 -0.3048)
			(stroke
				(width 0.1)
				(type default)
			)
			(layer "B.Fab")
		)
		(fp_line
			(start -0.67945 -0.3048)
			(end -0.67945 0.3048)
			(stroke
				(width 0.1)
				(type default)
			)
			(layer "B.Fab")
		)
		(fp_line
			(start 0.12065 -0.2794)
			(end -0.12065 -0.2794)
			(stroke
				(width 0.1)
				(type default)
			)
			(layer "B.Fab")
		)
		(fp_line
			(start -0.12065 -0.2794)
			(end -0.12065 -0.3048)
			(stroke
				(width 0.1)
				(type default)
			)
			(layer "B.Fab")
		)
		(fp_line
			(start 0.12065 0.2794)
			(end 0.12065 0.3048)
			(stroke
				(width 0.1)
				(type default)
			)
			(layer "B.Fab")
		)
		(fp_line
			(start -0.120396 0.2794)
			(end 0.12065 0.2794)
			(stroke
				(width 0.1)
				(type default)
			)
			(layer "B.Fab")
		)
		(fp_line
			(start 0.67945 0.3048)
			(end 0.67945 -0.305054)
			(stroke
				(width 0.1)
				(type default)
			)
			(layer "B.Fab")
		)
		(fp_line
			(start 0.12065 0.3048)
			(end 0.67945 0.3048)
			(stroke
				(width 0.1)
				(type default)
			)
			(layer "B.Fab")
		)
		(fp_line
			(start -0.120396 0.3048)
			(end -0.120396 0.2794)
			(stroke
				(width 0.1)
				(type default)
			)
			(layer "B.Fab")
		)
		(fp_line
			(start -0.67945 0.3048)
			(end -0.120396 0.3048)
			(stroke
				(width 0.1)
				(type default)
			)
			(layer "B.Fab")
		)
		(pad "1" smd circle
			(at 0.40005 0 270)
			(size 0 0)
			(layers "B.Cu" "B.Mask" "B.Paste")
			(net "P0V9_CPU0_RT1_2A")
		)
		(pad "2" smd circle
			(at -0.40005 0 270)
			(size 0 0)
			(layers "B.Cu" "B.Mask" "B.Paste")
			(net "GND")
		)
	)
	(footprint ""
		(layer "B.Cu")
		(at 25.92324 -194.885564 180)
		(property "Reference" "R6"
			(at 0 0 0)
			(layer "B.SilkS")
			(hide yes)
			(effects
				(font
					(size 1.27 1.27)
				)
				(justify mirror)
			)
		)
		(property "Value" ""
			(at 0 0 0)
			(layer "B.Fab")
			(effects
				(font
					(size 1.27 1.27)
				)
				(justify mirror)
			)
		)
		(duplicate_pad_numbers_are_jumpers no)
		(fp_line
			(start 0.7874 0.4064)
			(end 0.7874 -0.4064)
			(stroke
				(width 0.1524)
				(type default)
			)
			(layer "B.SilkS")
		)
		(fp_line
			(start 0.7874 -0.4064)
			(end -0.7874 -0.4064)
			(stroke
				(width 0.1524)
				(type default)
			)
			(layer "B.SilkS")
		)
		(fp_line
			(start -0.7874 0.4064)
			(end 0.7874 0.4064)
			(stroke
				(width 0.1524)
				(type default)
			)
			(layer "B.SilkS")
		)
		(fp_line
			(start -0.7874 -0.4064)
			(end -0.7874 0.4064)
			(stroke
				(width 0.1524)
				(type default)
			)
			(layer "B.SilkS")
		)
		(fp_line
			(start 0.67945 0.3048)
			(end 0.67945 -0.305054)
			(stroke
				(width 0.1)
				(type default)
			)
			(layer "B.Fab")
		)
		(fp_line
			(start 0.67945 -0.305054)
			(end 0.12065 -0.305054)
			(stroke
				(width 0.1)
				(type default)
			)
			(layer "B.Fab")
		)
		(fp_line
			(start 0.12065 0.3048)
			(end 0.67945 0.3048)
			(stroke
				(width 0.1)
				(type default)
			)
			(layer "B.Fab")
		)
		(fp_line
			(start 0.12065 0.2794)
			(end 0.12065 0.3048)
			(stroke
				(width 0.1)
				(type default)
			)
			(layer "B.Fab")
		)
		(fp_line
			(start 0.12065 -0.2794)
			(end -0.12065 -0.2794)
			(stroke
				(width 0.1)
				(type default)
			)
			(layer "B.Fab")
		)
		(fp_line
			(start 0.12065 -0.305054)
			(end 0.12065 -0.2794)
			(stroke
				(width 0.1)
				(type default)
			)
			(layer "B.Fab")
		)
		(fp_line
			(start -0.120396 0.3048)
			(end -0.120396 0.2794)
			(stroke
				(width 0.1)
				(type default)
			)
			(layer "B.Fab")
		)
		(fp_line
			(start -0.120396 0.2794)
			(end 0.12065 0.2794)
			(stroke
				(width 0.1)
				(type default)
			)
			(layer "B.Fab")
		)
		(fp_line
			(start -0.12065 -0.2794)
			(end -0.12065 -0.3048)
			(stroke
				(width 0.1)
				(type default)
			)
			(layer "B.Fab")
		)
		(fp_line
			(start -0.12065 -0.3048)
			(end -0.67945 -0.3048)
			(stroke
				(width 0.1)
				(type default)
			)
			(layer "B.Fab")
		)
		(fp_line
			(start -0.67945 0.3048)
			(end -0.120396 0.3048)
			(stroke
				(width 0.1)
				(type default)
			)
			(layer "B.Fab")
		)
		(fp_line
			(start -0.67945 -0.3048)
			(end -0.67945 0.3048)
			(stroke
				(width 0.1)
				(type default)
			)
			(layer "B.Fab")
		)
		(pad "1" smd circle
			(at 0.40005 0)
			(size 0 0)
			(layers "B.Cu" "B.Mask" "B.Paste")
			(net "PD_CHE_CPU1_DIMM_SAA")
		)
		(pad "2" smd circle
			(at -0.40005 0)
			(size 0 0)
			(layers "B.Cu" "B.Mask" "B.Paste")
			(net "GND")
		)
	)
	(footprint ""
		(layer "B.Cu")
		(at 215.0618 -336.296)
		(property "Reference" "R780"
			(at 0 0 0)
			(layer "B.SilkS")
			(hide yes)
			(effects
				(font
					(size 1.27 1.27)
				)
				(justify mirror)
			)
		)
		(property "Value" ""
			(at 0 0 0)
			(layer "B.Fab")
			(effects
				(font
					(size 1.27 1.27)
				)
				(justify mirror)
			)
		)
		(duplicate_pad_numbers_are_jumpers no)
		(fp_line
			(start -0.32512 -0.175006)
			(end -0.32512 0.175006)
			(stroke
				(width 0.1)
				(type default)
			)
			(layer "B.Fab")
		)
		(fp_line
			(start -0.32512 0.175006)
			(end 0.32512 0.175006)
			(stroke
				(width 0.1)
				(type default)
			)
			(layer "B.Fab")
		)
		(fp_line
			(start 0.32512 -0.175006)
			(end -0.32512 -0.175006)
			(stroke
				(width 0.1)
				(type default)
			)
			(layer "B.Fab")
		)
		(fp_line
			(start 0.32512 0.175006)
			(end 0.32512 -0.175006)
			(stroke
				(width 0.1)
				(type default)
			)
			(layer "B.Fab")
		)
		(pad "1" smd rect
			(at 0.2667 0 180)
			(size 0.3048 0.381)
			(layers "B.Cu" "B.Mask" "B.Paste")
			(net "SMB_RT_CPU1_P1_R_SDA")
		)
		(pad "2" smd rect
			(at -0.2667 0)
			(size 0.3048 0.381)
			(layers "B.Cu" "B.Mask" "B.Paste")
			(net "SMB_RT_CPU1_P1_R2_SDA")
		)
	)
	(footprint ""
		(layer "B.Cu")
		(at 136.874504 -31.874206 -90)
		(property "Reference" "C6047"
			(at 0 0 90)
			(layer "B.SilkS")
			(hide yes)
			(effects
				(font
					(size 1.27 1.27)
				)
				(justify mirror)
			)
		)
		(property "Value" ""
			(at 0 0 90)
			(layer "B.Fab")
			(effects
				(font
					(size 1.27 1.27)
				)
				(justify mirror)
			)
		)
		(duplicate_pad_numbers_are_jumpers no)
		(fp_line
			(start -0.7874 0.4064)
			(end 0.7874 0.4064)
			(stroke
				(width 0.1524)
				(type default)
			)
			(layer "B.SilkS")
		)
		(fp_line
			(start 0.7874 0.4064)
			(end 0.7874 -0.4064)
			(stroke
				(width 0.1524)
				(type default)
			)
			(layer "B.SilkS")
		)
		(fp_line
			(start -0.7874 -0.4064)
			(end -0.7874 0.4064)
			(stroke
				(width 0.1524)
				(type default)
			)
			(layer "B.SilkS")
		)
		(fp_line
			(start 0.7874 -0.4064)
			(end -0.7874 -0.4064)
			(stroke
				(width 0.1524)
				(type default)
			)
			(layer "B.SilkS")
		)
		(fp_line
			(start -0.67945 0.3048)
			(end -0.120396 0.3048)
			(stroke
				(width 0.1)
				(type default)
			)
			(layer "B.Fab")
		)
		(fp_line
			(start -0.120396 0.3048)
			(end -0.120396 0.2794)
			(stroke
				(width 0.1)
				(type default)
			)
			(layer "B.Fab")
		)
		(fp_line
			(start 0.12065 0.3048)
			(end 0.67945 0.3048)
			(stroke
				(width 0.1)
				(type default)
			)
			(layer "B.Fab")
		)
		(fp_line
			(start 0.67945 0.3048)
			(end 0.67945 -0.305054)
			(stroke
				(width 0.1)
				(type default)
			)
			(layer "B.Fab")
		)
		(fp_line
			(start -0.120396 0.2794)
			(end 0.12065 0.2794)
			(stroke
				(width 0.1)
				(type default)
			)
			(layer "B.Fab")
		)
		(fp_line
			(start 0.12065 0.2794)
			(end 0.12065 0.3048)
			(stroke
				(width 0.1)
				(type default)
			)
			(layer "B.Fab")
		)
		(fp_line
			(start -0.12065 -0.2794)
			(end -0.12065 -0.3048)
			(stroke
				(width 0.1)
				(type default)
			)
			(layer "B.Fab")
		)
		(fp_line
			(start 0.12065 -0.2794)
			(end -0.12065 -0.2794)
			(stroke
				(width 0.1)
				(type default)
			)
			(layer "B.Fab")
		)
		(fp_line
			(start -0.67945 -0.3048)
			(end -0.67945 0.3048)
			(stroke
				(width 0.1)
				(type default)
			)
			(layer "B.Fab")
		)
		(fp_line
			(start -0.12065 -0.3048)
			(end -0.67945 -0.3048)
			(stroke
				(width 0.1)
				(type default)
			)
			(layer "B.Fab")
		)
		(fp_line
			(start 0.12065 -0.305054)
			(end 0.12065 -0.2794)
			(stroke
				(width 0.1)
				(type default)
			)
			(layer "B.Fab")
		)
		(fp_line
			(start 0.67945 -0.305054)
			(end 0.12065 -0.305054)
			(stroke
				(width 0.1)
				(type default)
			)
			(layer "B.Fab")
		)
		(pad "1" smd circle
			(at 0.40005 0 90)
			(size 0 0)
			(layers "B.Cu" "B.Mask" "B.Paste")
			(net "P3V3_AUX")
		)
		(pad "2" smd circle
			(at -0.40005 0 90)
			(size 0 0)
			(layers "B.Cu" "B.Mask" "B.Paste")
			(net "GND")
		)
	)
)
